# T6G (Grand Teton) — schematic netlist excerpt (pin names and nets, part order shuffled) for the footprints in the layout excerpt that follows; sources: Cadence DE-HDL packaged netlist, KiCad conversion of 04192023_DAF0TMB3IC0_F0TG_MB_C_brd_V02_OCP.brd

PC2232  Q_CAP  0.047UF 25V 10% X7R  pkg C0402  page 152 : A = P12V_SCM_SS ; B = GND
PR8004  Q_RES  2.2 1% CHIP  pkg 0402LF  page 270 : A = SW_P1V2_AUX_BT ; B = SW_P1V2_AUX_BT_R

(kicad_pcb
	(version 20260206)
	(generator "pcbnew")
	(generator_version "10.0")
	(general
		(thickness 1.6)
		(legacy_teardrops no)
	)
	(paper "A4")
	(title_block
		(title "04192023_DAF0TMB3IC0_F0TG_MB_C_brd_V02_OCP.brd")
		(comment 1 "Grand Teton / footprints 4074-4075 of 8354")
	)
	(layers
		(0 "F.Cu" signal "TOP")
		(4 "In1.Cu" signal "GND")
		(6 "In2.Cu" signal "IN1")
		(8 "In3.Cu" signal "GND1")
		(10 "In4.Cu" signal "IN2")
		(12 "In5.Cu" signal "GND2")
		(14 "In6.Cu" signal "IN3")
		(16 "In7.Cu" signal "GND3")
		(18 "In8.Cu" signal "VCC")
		(20 "In9.Cu" signal "VCC1")
		(22 "In10.Cu" signal "GND4")
		(24 "In11.Cu" signal "IN4")
		(26 "In12.Cu" signal "GND5")
		(28 "In13.Cu" signal "IN5")
		(30 "In14.Cu" signal "GND6")
		(32 "In15.Cu" signal "IN6")
		(34 "In16.Cu" signal "GND7")
		(2 "B.Cu" signal "BOTTOM")
		(9 "F.Adhes" user "F.Adhesive")
		(11 "B.Adhes" user "B.Adhesive")
		(13 "F.Paste" user "Package Geometry/Pastemask Top")
		(15 "B.Paste" user "Package Geometry/Pastemask Bottom")
		(5 "F.SilkS" user "Ref Des/Silkscreen Top")
		(7 "B.SilkS" user "Ref Des/Silkscreen Bottom")
		(1 "F.Mask" user "Board Geometry/Soldermask Top")
		(3 "B.Mask" user "Board Geometry/Soldermask Bottom")
		(17 "Dwgs.User" user "User.Drawings")
		(19 "Cmts.User" user "User.Comments")
		(21 "Eco1.User" user "User.Eco1")
		(23 "Eco2.User" user "User.Eco2")
		(25 "Edge.Cuts" user "Board Geometry/Outline")
		(27 "Margin" user)
		(31 "F.CrtYd" user "Package Geometry/Place Bound Top")
		(29 "B.CrtYd" user "Package Geometry/Place Bound Bottom")
		(35 "F.Fab" user "Ref Des/Assembly Top")
		(33 "B.Fab" user "Ref Des/Assembly Bottom")
	)
	(footprint ""
		(layer "F.Cu")
		(at 176.391062 -32.935672 90)
		(property "Reference" "PC2232"
			(at 0 0 90)
			(layer "F.SilkS")
			(hide yes)
			(effects
				(font
					(size 1.27 1.27)
				)
			)
		)
		(property "Value" ""
			(at 0 0 90)
			(layer "F.Fab")
			(effects
				(font
					(size 1.27 1.27)
				)
			)
		)
		(duplicate_pad_numbers_are_jumpers no)
		(fp_line
			(start 0.7874 -0.4064)
			(end 0.7874 0.4064)
			(stroke
				(width 0.1524)
				(type default)
			)
			(layer "F.SilkS")
		)
		(fp_line
			(start -0.7874 -0.4064)
			(end 0.7874 -0.4064)
			(stroke
				(width 0.1524)
				(type default)
			)
			(layer "F.SilkS")
		)
		(fp_line
			(start 0.7874 0.4064)
			(end -0.7874 0.4064)
			(stroke
				(width 0.1524)
				(type default)
			)
			(layer "F.SilkS")
		)
		(fp_line
			(start -0.7874 0.4064)
			(end -0.7874 -0.4064)
			(stroke
				(width 0.1524)
				(type default)
			)
			(layer "F.SilkS")
		)
		(fp_line
			(start -0.12065 -0.305054)
			(end -0.12065 -0.2794)
			(stroke
				(width 0.1)
				(type default)
			)
			(layer "F.Fab")
		)
		(fp_line
			(start -0.67945 -0.305054)
			(end -0.12065 -0.305054)
			(stroke
				(width 0.1)
				(type default)
			)
			(layer "F.Fab")
		)
		(fp_line
			(start 0.67945 -0.3048)
			(end 0.67945 0.3048)
			(stroke
				(width 0.1)
				(type default)
			)
			(layer "F.Fab")
		)
		(fp_line
			(start 0.12065 -0.3048)
			(end 0.67945 -0.3048)
			(stroke
				(width 0.1)
				(type default)
			)
			(layer "F.Fab")
		)
		(fp_line
			(start 0.12065 -0.2794)
			(end 0.12065 -0.3048)
			(stroke
				(width 0.1)
				(type default)
			)
			(layer "F.Fab")
		)
		(fp_line
			(start -0.12065 -0.2794)
			(end 0.12065 -0.2794)
			(stroke
				(width 0.1)
				(type default)
			)
			(layer "F.Fab")
		)
		(fp_line
			(start 0.120396 0.2794)
			(end -0.12065 0.2794)
			(stroke
				(width 0.1)
				(type default)
			)
			(layer "F.Fab")
		)
		(fp_line
			(start -0.12065 0.2794)
			(end -0.12065 0.3048)
			(stroke
				(width 0.1)
				(type default)
			)
			(layer "F.Fab")
		)
		(fp_line
			(start 0.67945 0.3048)
			(end 0.120396 0.3048)
			(stroke
				(width 0.1)
				(type default)
			)
			(layer "F.Fab")
		)
		(fp_line
			(start 0.120396 0.3048)
			(end 0.120396 0.2794)
			(stroke
				(width 0.1)
				(type default)
			)
			(layer "F.Fab")
		)
		(fp_line
			(start -0.12065 0.3048)
			(end -0.67945 0.3048)
			(stroke
				(width 0.1)
				(type default)
			)
			(layer "F.Fab")
		)
		(fp_line
			(start -0.67945 0.3048)
			(end -0.67945 -0.305054)
			(stroke
				(width 0.1)
				(type default)
			)
			(layer "F.Fab")
		)
		(pad "1" smd circle
			(at -0.40005 0 90)
			(size 0 0)
			(layers "F.Cu" "F.Mask" "F.Paste")
			(net "P12V_SCM_SS")
		)
		(pad "2" smd circle
			(at 0.40005 0 90)
			(size 0 0)
			(layers "F.Cu" "F.Mask" "F.Paste")
			(net "GND")
		)
	)
	(footprint ""
		(layer "F.Cu")
		(at 124.090176 -74.555096 90)
		(property "Reference" "PR8004"
			(at 0 0 90)
			(layer "F.SilkS")
			(hide yes)
			(effects
				(font
					(size 1.27 1.27)
				)
			)
		)
		(property "Value" ""
			(at 0 0 90)
			(layer "F.Fab")
			(effects
				(font
					(size 1.27 1.27)
				)
			)
		)
		(duplicate_pad_numbers_are_jumpers no)
		(fp_line
			(start 0.7874 -0.4064)
			(end 0.7874 0.4064)
			(stroke
				(width 0.1524)
				(type default)
			)
			(layer "F.SilkS")
		)
		(fp_line
			(start -0.7874 -0.4064)
			(end 0.7874 -0.4064)
			(stroke
				(width 0.1524)
				(type default)
			)
			(layer "F.SilkS")
		)
		(fp_line
			(start 0.7874 0.4064)
			(end -0.7874 0.4064)
			(stroke
				(width 0.1524)
				(type default)
			)
			(layer "F.SilkS")
		)
		(fp_line
			(start -0.7874 0.4064)
			(end -0.7874 -0.4064)
			(stroke
				(width 0.1524)
				(type default)
			)
			(layer "F.SilkS")
		)
		(fp_line
			(start -0.12065 -0.305054)
			(end -0.12065 -0.2794)
			(stroke
				(width 0.1)
				(type default)
			)
			(layer "F.Fab")
		)
		(fp_line
			(start -0.67945 -0.305054)
			(end -0.12065 -0.305054)
			(stroke
				(width 0.1)
				(type default)
			)
			(layer "F.Fab")
		)
		(fp_line
			(start 0.67945 -0.3048)
			(end 0.67945 0.3048)
			(stroke
				(width 0.1)
				(type default)
			)
			(layer "F.Fab")
		)
		(fp_line
			(start 0.12065 -0.3048)
			(end 0.67945 -0.3048)
			(stroke
				(width 0.1)
				(type default)
			)
			(layer "F.Fab")
		)
		(fp_line
			(start 0.12065 -0.2794)
			(end 0.12065 -0.3048)
			(stroke
				(width 0.1)
				(type default)
			)
			(layer "F.Fab")
		)
		(fp_line
			(start -0.12065 -0.2794)
			(end 0.12065 -0.2794)
			(stroke
				(width 0.1)
				(type default)
			)
			(layer "F.Fab")
		)
		(fp_line
			(start 0.120396 0.2794)
			(end -0.12065 0.2794)
			(stroke
				(width 0.1)
				(type default)
			)
			(layer "F.Fab")
		)
		(fp_line
			(start -0.12065 0.2794)
			(end -0.12065 0.3048)
			(stroke
				(width 0.1)
				(type default)
			)
			(layer "F.Fab")
		)
		(fp_line
			(start 0.67945 0.3048)
			(end 0.120396 0.3048)
			(stroke
				(width 0.1)
				(type default)
			)
			(layer "F.Fab")
		)
		(fp_line
			(start 0.120396 0.3048)
			(end 0.120396 0.2794)
			(stroke
				(width 0.1)
				(type default)
			)
			(layer "F.Fab")
		)
		(fp_line
			(start -0.12065 0.3048)
			(end -0.67945 0.3048)
			(stroke
				(width 0.1)
				(type default)
			)
			(layer "F.Fab")
		)
		(fp_line
			(start -0.67945 0.3048)
			(end -0.67945 -0.305054)
			(stroke
				(width 0.1)
				(type default)
			)
			(layer "F.Fab")
		)
		(pad "1" smd circle
			(at -0.40005 0 90)
			(size 0 0)
			(layers "F.Cu" "F.Mask" "F.Paste")
			(net "SW_P1V2_AUX_BT")
		)
		(pad "2" smd circle
			(at 0.40005 0 90)
			(size 0 0)
			(layers "F.Cu" "F.Mask" "F.Paste")
			(net "SW_P1V2_AUX_BT_R")
		)
	)
)
